FILE_TYPE = CONNECTIVITY;
{Allegro Design Entry HDL 17.4-2019 S026 (4007227) 1/17/2022}
"PAGE_NUMBER" = 364;
0"NC";
1"P3V3_AUX\g";
2"GND\g";
3"GND\g";
4"GND\g";
5"P3V3_AUX\g";
6"GND\g";
7"GND\g";
8"GND\g";
9"P3V3_AUX\g";
10"P3V3_AUX\g";
11"GND\g";
12"P3V3_AUX\g";
13"GND\g";
14"GND\g";
15"P3V3_AUX\g";
16"GND\g";
17"GND\g";
18"PWRGD_P3V3_AUX_PDB";
19"HPDB_HSC_PWRGD_N";
20"GPU_PRSNT_R";
21"HPDB_HSC_PWRGD";
22"FM_GPU_HSC_EN";
23"GPU_PRSNT";
24"FM_GPU_HSC_EN_BUF_R";
25"P3V3_AUX\g";
26"P3V3_AUX\g";
27"PWRGD_P3V3_AUX_PDB_BUF_R";
28"PWRGD_P3V3_AUX_PDB_R";
29"PWRGD_P3V3_AUX_PDB_BUF";
30"FM_GPU_HSC_EN_BUF";
31"HPDB_HSC_PWRGD_ISO";
%"UNIVERSAL_POWER"
"1","(-1800,3350)","0","pure_quanta_power","I10";
;
HDL_POWER"P3V3_AUX"
CDS_LIB"pure_quanta_power";
"A"1;
%"UNIVERSAL_GND"
"1","(-150,1850)","0","pure_quanta_power","I12";
;
CDS_LIB"pure_quanta_power"
HDL_POWER"GND";
"A"2;
%"UNIVERSAL_GND"
"1","(925,2250)","0","pure_quanta_power","I13";
;
CDS_LIB"pure_quanta_power"
HDL_POWER"GND";
"A"3;
%"Q_CAP"
"1","(925,2475)","0","pure_quanta","I14";
;
LOCATION"C1775"
$SEC"1"
CDS_SEC"1"
PACK_TYPE"0402"
VALUE"0.1UF"
MATERIAL"X7R"
VOLTAGE"25V"
TOLERANCE"10%"
CDS_LIB"pure_quanta"
PART_NUMBER"CH4104K1B00";
"B"
$PN"2"3;
"A"
$PN"1"25;
%"UNIVERSAL_POWER"
"1","(925,2800)","0","pure_quanta_power","I15";
;
HDL_POWER"P3V3_AUX"
CDS_LIB"pure_quanta_power";
"A"25;
%"UNIVERSAL_GND"
"1","(1750,1550)","0","pure_quanta_power","I22";
;
CDS_LIB"pure_quanta_power"
HDL_POWER"GND";
"A"4;
%"Q_RES"
"1","(2000,2075)","0","pure_quanta","I24";
;
LOCATION"R2944"
$SEC"1"
CDS_SEC"1"
VALUE"33.2"
MATERIAL"CHIP"
PACK_TYPE"0402LF"
WATTAGE"1/16W"
TOLERANCE"1%"
CDS_LIB"pure_quanta"
PART_NUMBER"CS03322FB03";
"B"
$PN"2"30;
"A"
$PN"1"24;
%"Q_RES"
"2","(1725,2325)","0","pure_quanta","I25";
;
LOCATION"R2946"
$SEC"1"
CDS_SEC"1"
PACK_TYPE"0402LF"
MATERIAL"EMPTY"
WATTAGE"1/16W"
TOLERANCE"5%"
VALUE"4.7K"
CDS_LIB"pure_quanta"
PART_NUMBER"CS24702JB10";
"A"
$PN"1"5;
"B"
$PN"2"24;
%"UNIVERSAL_POWER"
"1","(1725,2575)","0","pure_quanta_power","I26";
;
HDL_POWER"P3V3_AUX"
CDS_LIB"pure_quanta_power";
"A"5;
%"Q_RES"
"2","(-1800,3100)","0","pure_quanta","I28";
;
LOCATION"R2940"
$SEC"1"
CDS_SEC"1"
WATTAGE"1/16W"
MATERIAL"EMPTY"
PACK_TYPE"0402LF"
TOLERANCE"5%"
VALUE"4.7K"
CDS_LIB"pure_quanta"
PART_NUMBER"CS24702JB10";
"A"
$PN"1"1;
"B"
$PN"2"22;
%"Q_RES"
"2","(-1775,2625)","0","pure_quanta","I29";
;
LOCATION"R2941"
$SEC"1"
CDS_SEC"1"
VALUE"100K"
MATERIAL"CHIP"
WATTAGE"1/16W"
TOLERANCE"1%"
PACK_TYPE"0402LF"
CDS_LIB"pure_quanta"
PART_NUMBER"CS41002FB09";
"A"
$PN"1"22;
"B"
$PN"2"14;
%"Q_RES"
"2","(1750,1775)","0","pure_quanta","I30";
;
LOCATION"R2948"
$SEC"1"
CDS_SEC"1"
VALUE"4.7K"
PACK_TYPE"0402LF"
TOLERANCE"5%"
MATERIAL"EMPTY"
WATTAGE"1/16W"
CDS_LIB"pure_quanta"
PART_NUMBER"CS24702JB10";
"A"
$PN"1"24;
"B"
$PN"2"4;
%"74LVC1G08W57"
"1","(250,2125)","0","pure_quanta","I31";
;
LOCATION"U278"
$SEC"1"
CDS_SEC"1"
MATERIAL"IC"
VALUE"74LVC1G08W5-7"
PART_TYPE"SMLF"
NEEDS_NO_SIZE"TRUE"
CDS_LMAN_SYM_OUTLINE"-150,150,150,-150"
CDS_LIB"pure_quanta"
PART_NUMBER"AL1G0008020";
"VCC"
$PN"5"25;
"Y"
$PN"4"24;
"GND"
$PN"3"2;
"B"
$PN"2"20;
"A"
$PN"1"22;
%"Q_RES"
"1","(-1325,2125)","0","pure_quanta","I34";
;
LOCATION"R3770"
$SEC"1"
CDS_SEC"1"
PACK_TYPE"0402LF"
VALUE"0"
TOLERANCE"5%"
MATERIAL"CHIP"
WATTAGE"1/16W"
CDS_LIB"pure_quanta"
PART_NUMBER"CS00002JB13";
"B"
$PN"2"20;
"A"
$PN"1"23;
%"UNIVERSAL_GND"
"1","(-25,75)","0","pure_quanta_power","I36";
;
CDS_LIB"pure_quanta_power"
HDL_POWER"GND";
"A"6;
%"74LVC2G07DW7"
"1","(550,225)","0","pure_quanta","I37";
;
LOCATION"U308"
$SEC"1"
CDS_SEC"1"
MATERIAL"IC"
PART_TYPE"SMLF"
VALUE"74LVC2G07DW-7"
CDS_LMAN_SYM_OUTLINE"-175,100,175,-100"
NEEDS_NO_SIZE"TRUE"
CDS_LIB"pure_quanta"
PART_NUMBER"AL002G07003";
"VCC"
$PN"5"26;
"GND"
$PN"2"6;
"2Y"
$PN"4"0;
"1Y"
$PN"6"27;
"2A"
$PN"3"0;
"1A"
$PN"1"28;
%"UNIVERSAL_POWER"
"1","(1250,-25)","0","pure_quanta_power","I38";
;
HDL_POWER"P3V3_AUX"
CDS_LIB"pure_quanta_power";
"A"26;
%"UNIVERSAL_GND"
"1","(1250,-575)","0","pure_quanta_power","I39";
;
CDS_LIB"pure_quanta_power"
HDL_POWER"GND";
"A"7;
%"Q_CAP"
"1","(1250,-350)","0","pure_quanta","I40";
;
LOCATION"C69"
$SEC"1"
CDS_SEC"1"
MATERIAL"X7R"
TOLERANCE"10%"
VOLTAGE"25V"
PACK_TYPE"0402"
VALUE"0.1UF"
CDS_LIB"pure_quanta"
PART_NUMBER"CH4104K1B00";
"B"
$PN"2"7;
"A"
$PN"1"26;
%"Q_RES"
"1","(-1125,275)","0","pure_quanta","I41";
;
LOCATION"R4268"
$SEC"1"
CDS_SEC"1"
TOLERANCE"5%"
MATERIAL"CHIP"
WATTAGE"1/16W"
PACK_TYPE"0402LF"
VALUE"0"
CDS_LIB"pure_quanta"
PART_NUMBER"CS00002JB13";
"B"
$PN"2"28;
"A"
$PN"1"18;
%"Q_RES"
"2","(2175,-25)","0","pure_quanta","I43";
;
LOCATION"R4265"
$SEC"1"
CDS_SEC"1"
PACK_TYPE"0402LF"
WATTAGE"1/16W"
MATERIAL"EMPTY"
TOLERANCE"5%"
VALUE"4.7K"
CDS_LIB"pure_quanta"
PART_NUMBER"CS24702JB10";
"A"
$PN"1"27;
"B"
$PN"2"8;
%"UNIVERSAL_GND"
"1","(2175,-250)","0","pure_quanta_power","I44";
;
CDS_LIB"pure_quanta_power"
HDL_POWER"GND";
"A"8;
%"UNIVERSAL_POWER"
"1","(2150,775)","0","pure_quanta_power","I46";
;
HDL_POWER"P3V3_AUX"
CDS_LIB"pure_quanta_power";
"A"9;
%"Q_RES"
"2","(2150,525)","0","pure_quanta","I47";
;
LOCATION"R4264"
$SEC"1"
CDS_SEC"1"
MATERIAL"CHIP"
WATTAGE"1/16W"
PACK_TYPE"0402LF"
TOLERANCE"5%"
VALUE"4.7K"
CDS_LIB"pure_quanta"
PART_NUMBER"CS24702JB10";
"A"
$PN"1"9;
"B"
$PN"2"27;
%"Q_RES"
"1","(2400,275)","0","pure_quanta","I48";
;
LOCATION"R4266"
$SEC"1"
CDS_SEC"1"
VALUE"33.2"
PACK_TYPE"0402LF"
MATERIAL"CHIP"
WATTAGE"1/16W"
TOLERANCE"1%"
CDS_LIB"pure_quanta"
PART_NUMBER"CS03322FB03";
"B"
$PN"2"29;
"A"
$PN"1"27;
%"Q_RES"
"2","(-1100,-2275)","0","pure_quanta","I50";
;
LOCATION"R4552"
$SEC"1"
CDS_SEC"1"
MATERIAL"CHIP"
WATTAGE"1/16W"
TOLERANCE"1%"
VALUE"100K"
PACK_TYPE"0402LF"
CDS_LIB"pure_quanta"
PART_NUMBER"CS41002FB09";
"A"
$PN"1"21;
"B"
$PN"2"17;
%"Q_RES"
"2","(-1125,-1800)","0","pure_quanta","I51";
;
LOCATION"R4551"
$SEC"1"
CDS_SEC"1"
WATTAGE"1/16W"
PACK_TYPE"0402LF"
MATERIAL"EMPTY"
TOLERANCE"1%"
VALUE"54.9K"
CDS_LIB"pure_quanta"
PART_NUMBER"CS35492FB03";
"A"
$PN"1"10;
"B"
$PN"2"21;
%"UNIVERSAL_POWER"
"1","(-1125,-1550)","0","pure_quanta_power","I52";
;
HDL_POWER"P3V3_AUX"
CDS_LIB"pure_quanta_power";
"A"10;
%"MOSFET_NCH_DUAL"
"1","(0,-2025)","0","pure_quanta","I53";
;
LOCATION"Q145"
$SEC"1"
CDS_SEC"1"
VALUE"PJT138K"
MATERIAL"IC"
PART_TYPE"SMLF"
CDS_LMAN_SYM_OUTLINE"-150,150,150,-150"
NEEDS_NO_SIZE"TRUE"
CDS_LIB"pure_quanta"
PART_NUMBER"BAM138K0003";
"D1"
$PN"6"19;
"G1"
$PN"2"21;
"S1"
$PN"1"11;
%"UNIVERSAL_GND"
"1","(50,-2400)","0","pure_quanta_power","I54";
;
CDS_LIB"pure_quanta_power"
HDL_POWER"GND";
"A"11;
%"Q_RES"
"2","(50,-1425)","0","pure_quanta","I55";
;
LOCATION"R4553"
$SEC"1"
CDS_SEC"1"
VALUE"4.7K"
TOLERANCE"5%"
WATTAGE"1/16W"
MATERIAL"CHIP"
PACK_TYPE"0402LF"
CDS_LIB"pure_quanta"
PART_NUMBER"CS24702JB10";
"A"
$PN"1"12;
"B"
$PN"2"19;
%"UNIVERSAL_POWER"
"1","(50,-1200)","0","pure_quanta_power","I56";
;
HDL_POWER"P3V3_AUX"
CDS_LIB"pure_quanta_power";
"A"12;
%"UNIVERSAL_GND"
"1","(1200,-2100)","0","pure_quanta_power","I57";
;
CDS_LIB"pure_quanta_power"
HDL_POWER"GND";
"A"13;
%"MOSFET_NCH_DUAL"
"2","(1150,-1725)","0","pure_quanta","I58";
;
LOCATION"Q145"
$SEC"2"
CDS_SEC"2"
PART_TYPE"SMLF"
MATERIAL"IC"
VALUE"PJT138K"
CDS_LIB"pure_quanta"
NEEDS_NO_SIZE"TRUE"
CDS_LMAN_SYM_OUTLINE"-150,150,150,-150"
PART_NUMBER"BAM138K0003";
"S2"
$PN"4"13;
"G2"
$PN"5"19;
"D2"
$PN"3"31;
%"Q_RES"
"2","(1200,-1300)","0","pure_quanta","I59";
;
LOCATION"R4554"
$SEC"1"
CDS_SEC"1"
MATERIAL"CHIP"
PACK_TYPE"0402LF"
VALUE"100K"
TOLERANCE"1%"
WATTAGE"1/16W"
CDS_LIB"pure_quanta"
PART_NUMBER"CS41002FB09";
"A"
$PN"1"15;
"B"
$PN"2"31;
%"UNIVERSAL_GND"
"1","(-1775,2425)","0","pure_quanta_power","I6";
;
CDS_LIB"pure_quanta_power"
HDL_POWER"GND";
"A"14;
%"UNIVERSAL_POWER"
"1","(1200,-1075)","0","pure_quanta_power","I60";
;
HDL_POWER"P3V3_AUX"
CDS_LIB"pure_quanta_power";
"A"15;
%"UNIVERSAL_GND"
"1","(1975,-1975)","0","pure_quanta_power","I61";
;
CDS_LIB"pure_quanta_power"
HDL_POWER"GND";
"A"16;
%"Q_CAP"
"1","(1975,-1775)","0","pure_quanta","I62";
;
LOCATION"C70"
$SEC"1"
CDS_SEC"1"
VALUE"0.1UF"
VOLTAGE"25V"
TOLERANCE"10%"
MATERIAL"X7R"
PACK_TYPE"0402"
CDS_LIB"pure_quanta"
PART_NUMBER"CH4104K1B00";
"B"
$PN"2"16;
"A"
$PN"1"31;
%"UNIVERSAL_GND"
"1","(-1100,-2550)","0","pure_quanta_power","I64";
;
CDS_LIB"pure_quanta_power"
HDL_POWER"GND";
"A"17;
END.
